# T6G (Grand Teton) — schematic netlist excerpt (pin names and nets, part order shuffled) for the footprints in the layout excerpt that follows; sources: Cadence DE-HDL packaged netlist, KiCad conversion of 04192023_DAF0TMB3IC0_F0TG_MB_C_brd_V02_OCP.brd

J13  CONN4_HFK1040L0P1L7H  CONN4_HFK1040-L0P1L-7H IO  pkg HEADER1X4BHXA  page 164
  \1\  = UART_VCC_J13
  \2\  = UART_CPU0_LVC3_UART0_RX
  \3\  = UART_CPU0_LVC3_UART0_TX
  \4\  = GND

(kicad_pcb
	(version 20260206)
	(generator "pcbnew")
	(generator_version "10.0")
	(general
		(thickness 1.6)
		(legacy_teardrops no)
	)
	(paper "A4")
	(title_block
		(title "04192023_DAF0TMB3IC0_F0TG_MB_C_brd_V02_OCP.brd")
		(comment 1 "Grand Teton / footprints 581-581 of 8354")
	)
	(layers
		(0 "F.Cu" signal "TOP")
		(4 "In1.Cu" signal "GND")
		(6 "In2.Cu" signal "IN1")
		(8 "In3.Cu" signal "GND1")
		(10 "In4.Cu" signal "IN2")
		(12 "In5.Cu" signal "GND2")
		(14 "In6.Cu" signal "IN3")
		(16 "In7.Cu" signal "GND3")
		(18 "In8.Cu" signal "VCC")
		(20 "In9.Cu" signal "VCC1")
		(22 "In10.Cu" signal "GND4")
		(24 "In11.Cu" signal "IN4")
		(26 "In12.Cu" signal "GND5")
		(28 "In13.Cu" signal "IN5")
		(30 "In14.Cu" signal "GND6")
		(32 "In15.Cu" signal "IN6")
		(34 "In16.Cu" signal "GND7")
		(2 "B.Cu" signal "BOTTOM")
		(9 "F.Adhes" user "F.Adhesive")
		(11 "B.Adhes" user "B.Adhesive")
		(13 "F.Paste" user "Package Geometry/Pastemask Top")
		(15 "B.Paste" user "Package Geometry/Pastemask Bottom")
		(5 "F.SilkS" user "Ref Des/Silkscreen Top")
		(7 "B.SilkS" user "Ref Des/Silkscreen Bottom")
		(1 "F.Mask" user "Board Geometry/Soldermask Top")
		(3 "B.Mask" user "Board Geometry/Soldermask Bottom")
		(17 "Dwgs.User" user "User.Drawings")
		(19 "Cmts.User" user "User.Comments")
		(21 "Eco1.User" user "User.Eco1")
		(23 "Eco2.User" user "User.Eco2")
		(25 "Edge.Cuts" user "Board Geometry/Outline")
		(27 "Margin" user)
		(31 "F.CrtYd" user "Package Geometry/Place Bound Top")
		(29 "B.CrtYd" user "Package Geometry/Place Bound Bottom")
		(35 "F.Fab" user "Ref Des/Assembly Top")
		(33 "B.Fab" user "Ref Des/Assembly Bottom")
	)
	(footprint ""
		(layer "F.Cu")
		(at 363.51845 -22.207728 90)
		(property "Reference" "J13"
			(at -3.17754 -2.820924 90)
			(unlocked yes)
			(layer "F.SilkS")
			(effects
				(font
					(size 0.7874 0.5842)
					(thickness 0.1524)
				)
				(justify left)
			)
		)
		(property "Value" ""
			(at 0 0 90)
			(layer "F.Fab")
			(effects
				(font
					(size 1.27 1.27)
				)
			)
		)
		(duplicate_pad_numbers_are_jumpers no)
		(fp_line
			(start 1.700022 -1.999996)
			(end -2.999994 -1.999996)
			(stroke
				(width 0.1524)
				(type default)
			)
			(layer "F.SilkS")
		)
		(fp_line
			(start -2.999994 -1.999996)
			(end -2.999994 7.999984)
			(stroke
				(width 0.1524)
				(type default)
			)
			(layer "F.SilkS")
		)
		(fp_line
			(start 1.199896 -1.500124)
			(end 1.199896 0.999998)
			(stroke
				(width 0.1524)
				(type default)
			)
			(layer "F.SilkS")
		)
		(fp_line
			(start -2.500122 -1.500124)
			(end 1.199896 -1.500124)
			(stroke
				(width 0.1524)
				(type default)
			)
			(layer "F.SilkS")
		)
		(fp_line
			(start 1.199896 0.999998)
			(end 1.700022 0.999998)
			(stroke
				(width 0.1524)
				(type default)
			)
			(layer "F.SilkS")
		)
		(fp_line
			(start 1.700022 4.99999)
			(end 1.199896 4.99999)
			(stroke
				(width 0.1524)
				(type default)
			)
			(layer "F.SilkS")
		)
		(fp_line
			(start 1.199896 4.99999)
			(end 1.199896 7.500112)
			(stroke
				(width 0.1524)
				(type default)
			)
			(layer "F.SilkS")
		)
		(fp_line
			(start -2.500122 5.425694)
			(end -2.500122 -1.500124)
			(stroke
				(width 0.1524)
				(type default)
			)
			(layer "F.SilkS")
		)
		(fp_line
			(start 1.199896 7.500112)
			(end -2.500122 7.500112)
			(stroke
				(width 0.1524)
				(type default)
			)
			(layer "F.SilkS")
		)
		(fp_line
			(start -2.500122 7.500112)
			(end -2.500122 6.568694)
			(stroke
				(width 0.1524)
				(type default)
			)
			(layer "F.SilkS")
		)
		(fp_line
			(start 1.700022 7.999984)
			(end 1.700022 -1.999996)
			(stroke
				(width 0.1524)
				(type default)
			)
			(layer "F.SilkS")
		)
		(fp_line
			(start -0.899922 7.999984)
			(end 1.700022 7.999984)
			(stroke
				(width 0.1524)
				(type default)
			)
			(layer "F.SilkS")
		)
		(fp_line
			(start -2.999994 7.999984)
			(end -0.899922 7.999984)
			(stroke
				(width 0.1524)
				(type default)
			)
			(layer "F.SilkS")
		)
		(fp_poly
			(pts
				(xy 0.762 -3.731006) (xy 0 -2.207006) (xy -0.762 -3.731006)
			)
			(stroke
				(width 0)
				(type default)
			)
			(fill yes)
			(layer "F.SilkS")
		)
		(fp_line
			(start 1.700022 -1.999996)
			(end -2.999994 -1.999996)
			(stroke
				(width 0.1)
				(type default)
			)
			(layer "F.Fab")
		)
		(fp_line
			(start -2.999994 -1.999996)
			(end -2.999994 7.999984)
			(stroke
				(width 0.1)
				(type default)
			)
			(layer "F.Fab")
		)
		(fp_line
			(start 1.199896 -1.500124)
			(end 1.199896 0.999998)
			(stroke
				(width 0.1)
				(type default)
			)
			(layer "F.Fab")
		)
		(fp_line
			(start -2.500122 -1.500124)
			(end 1.199896 -1.500124)
			(stroke
				(width 0.1)
				(type default)
			)
			(layer "F.Fab")
		)
		(fp_line
			(start 1.199896 0.999998)
			(end 1.700022 0.999998)
			(stroke
				(width 0.1)
				(type default)
			)
			(layer "F.Fab")
		)
		(fp_line
			(start 1.700022 4.99999)
			(end 1.199896 4.99999)
			(stroke
				(width 0.1)
				(type default)
			)
			(layer "F.Fab")
		)
		(fp_line
			(start 1.199896 4.99999)
			(end 1.199896 7.500112)
			(stroke
				(width 0.1)
				(type default)
			)
			(layer "F.Fab")
		)
		(fp_line
			(start -2.500122 6.657594)
			(end -2.500122 -1.500124)
			(stroke
				(width 0.1)
				(type default)
			)
			(layer "F.Fab")
		)
		(fp_line
			(start 1.199896 7.500112)
			(end -2.500122 7.500112)
			(stroke
				(width 0.1)
				(type default)
			)
			(layer "F.Fab")
		)
		(fp_line
			(start -2.500122 7.500112)
			(end -2.500122 6.606794)
			(stroke
				(width 0.1)
				(type default)
			)
			(layer "F.Fab")
		)
		(fp_line
			(start 1.700022 7.999984)
			(end 1.700022 -1.999996)
			(stroke
				(width 0.1)
				(type default)
			)
			(layer "F.Fab")
		)
		(fp_line
			(start -0.899922 7.999984)
			(end 1.700022 7.999984)
			(stroke
				(width 0.1)
				(type default)
			)
			(layer "F.Fab")
		)
		(fp_line
			(start -2.999994 7.999984)
			(end -0.899922 7.999984)
			(stroke
				(width 0.1)
				(type default)
			)
			(layer "F.Fab")
		)
		(fp_poly
			(pts
				(xy 0 -2.207006) (xy -0.762 -3.731006) (xy 0.762 -3.731006)
			)
			(stroke
				(width 0)
				(type default)
			)
			(fill yes)
			(layer "F.Fab")
		)
		(pad "" np_thru_hole circle
			(at -1.800098 5.999988 180)
			(size 1.143 1.143)
			(drill 1.143)
			(layers "*.Cu" "*.Mask")
			(clearance 0.381)
			(thermal_gap 0.381)
		)
		(pad "1" thru_hole rect
			(at 0 0 180)
			(size 1.2192 1.2192)
			(drill 0.8128)
			(layers "*.Cu" "*.Mask")
			(remove_unused_layers no)
			(net "UART_VCC_J13")
			(clearance 0.0508)
			(thermal_gap 0.0508)
			(padstack
				(mode front_inner_back)
				(layer "Inner"
					(shape circle)
					(size 1.2192 1.2192)
					(clearance 0.0508)
				)
				(layer "B.Cu"
					(shape rect)
					(size 1.2192 1.2192)
					(clearance 0.0508)
				)
			)
		)
		(pad "2" thru_hole circle
			(at 0 1.999996 180)
			(size 1.2192 1.2192)
			(drill 0.8128)
			(layers "*.Cu" "*.Mask")
			(remove_unused_layers no)
			(net "UART_CPU0_LVC3_UART0_RX")
			(clearance 0.0508)
			(thermal_gap 0.0508)
		)
		(pad "3" thru_hole circle
			(at 0 3.999992 180)
			(size 1.2192 1.2192)
			(drill 0.8128)
			(layers "*.Cu" "*.Mask")
			(remove_unused_layers no)
			(net "UART_CPU0_LVC3_UART0_TX")
			(clearance 0.0508)
			(thermal_gap 0.0508)
		)
		(pad "4" thru_hole circle
			(at 0 5.999988 180)
			(size 1.2192 1.2192)
			(drill 0.8128)
			(layers "*.Cu" "*.Mask")
			(remove_unused_layers no)
			(net "GND")
			(clearance 0.0508)
			(thermal_gap 0.0508)
		)
		(zone
			(layers "F.Cu" "B.Cu" "In1.Cu" "In2.Cu" "In3.Cu" "In4.Cu" "In5.Cu" "In6.Cu"
				"In7.Cu" "In8.Cu" "In9.Cu" "In10.Cu" "In11.Cu" "In12.Cu" "In13.Cu" "In14.Cu"
				"In15.Cu" "In16.Cu"
			)
			(hatch none 0.5)
			(connect_pads
				(clearance 0)
			)
			(min_thickness 0.25)
			(keepout
				(tracks not_allowed)
				(vias allowed)
				(pads allowed)
				(copperpour not_allowed)
				(footprints allowed)
			)
			(placement
				(enabled no)
				(sheetname "")
			)
			(fill
				(thermal_gap 0.5)
				(thermal_bridge_width 0.5)
				(island_removal_mode 0)
			)
			(polygon
				(pts
					(arc
						(start 370.536724 -20.418806)
						(mid 370.237657 -19.696793)
						(end 369.515644 -19.397726)
					)
					(arc
						(start 369.515644 -19.397726)
						(mid 368.507264 -20.406106)
						(end 369.515644 -21.414486)
					)
					(arc
						(start 369.541044 -21.414486)
						(mid 370.245096 -21.122858)
						(end 370.536724 -20.418806)
					)
				)
			)
		)
	)
)
